(kicad_pcb
	(version 20260206)
	(generator "pcbnew")
	(generator_version "10.0")
	(general
		(thickness 1.6)
		(legacy_teardrops no)
	)
	(paper "A4")
	(title_block
		(title "baseboard — 13948-1b.1110WZS1818.brd")
		(comment 1 "Honey Badger (Wiwynn) / footprints 2222-2229 of 2523")
	)
	(layers
		(0 "F.Cu" signal "TOP")
		(4 "In1.Cu" signal "L2GND")
		(6 "In2.Cu" signal "L3")
		(8 "In3.Cu" signal "L4VCC")
		(10 "In4.Cu" signal "L5VCC")
		(12 "In5.Cu" signal "L6")
		(14 "In6.Cu" signal "L7GND")
		(2 "B.Cu" signal "BOTTOM")
		(9 "F.Adhes" user "F.Adhesive")
		(11 "B.Adhes" user "B.Adhesive")
		(13 "F.Paste" user "Package Geometry/Pastemask Top")
		(15 "B.Paste" user "Package Geometry/Pastemask Bottom")
		(5 "F.SilkS" user "Ref Des/Silkscreen Top")
		(7 "B.SilkS" user "Ref Des/Silkscreen Bottom")
		(1 "F.Mask" user "Board Geometry/Soldermask Top")
		(3 "B.Mask" user "Board Geometry/Soldermask Bottom")
		(17 "Dwgs.User" user "User.Drawings")
		(19 "Cmts.User" user "User.Comments")
		(21 "Eco1.User" user "User.Eco1")
		(23 "Eco2.User" user "User.Eco2")
		(25 "Edge.Cuts" user "Board Geometry/Outline")
		(27 "Margin" user)
		(31 "F.CrtYd" user "Package Geometry/Place Bound Top")
		(29 "B.CrtYd" user "Package Geometry/Place Bound Bottom")
		(35 "F.Fab" user "Ref Des/Assembly Top")
		(33 "B.Fab" user "Ref Des/Assembly Bottom")
	)
	(footprint ""
		(layer "B.Cu")
		(at 115.551966 -33.02)
		(property "Reference" "STP140"
			(at 0 0 0)
			(layer "B.SilkS")
			(hide yes)
			(effects
				(font
					(size 1.27 1.27)
				)
				(justify mirror)
			)
		)
		(property "Value" "TPAD28"
			(at -0.0127 -1.8034 0)
			(unlocked yes)
			(layer "B.Fab")
			(hide yes)
			(effects
				(font
					(size 1.016 1.016)
					(thickness 0.1524)
				)
				(justify mirror)
			)
		)
		(property "Device Type" "TPAD28"
			(at -0.0127 -3.3274 0)
			(unlocked yes)
			(layer "B.Fab")
			(hide yes)
			(effects
				(font
					(size 1.016 1.016)
					(thickness 0.1524)
				)
				(justify mirror)
			)
		)
		(duplicate_pad_numbers_are_jumpers no)
		(fp_poly
			(pts
				(arc
					(start 0.3556 0)
					(mid -0.3556 0)
					(end 0.3556 0)
				)
			)
			(stroke
				(width 0)
				(type default)
			)
			(fill no)
			(layer "B.CrtYd")
		)
		(fp_poly
			(pts
				(arc
					(start 0.6096 0)
					(mid -0.6096 0)
					(end 0.6096 0)
				)
			)
			(stroke
				(width 0)
				(type default)
			)
			(fill no)
			(layer "B.Fab")
		)
		(pad "1" smd circle
			(at 0 0 180)
			(size 0.7112 0.7112)
			(layers "B.Cu" "B.Mask" "B.Paste")
			(net "IOC_GPIO_21")
		)
	)
	(footprint ""
		(layer "B.Cu")
		(at 81.407 -73.279)
		(property "Reference" "PU99"
			(at 0 0 0)
			(layer "B.SilkS")
			(hide yes)
			(effects
				(font
					(size 1.27 1.27)
				)
				(justify mirror)
			)
		)
		(property "Value" "SNLVC1G17DCKR-GP"
			(at 2.3368 -8.6868 0)
			(unlocked yes)
			(layer "B.Fab")
			(hide yes)
			(effects
				(font
					(size 1.016 1.016)
					(thickness 0.1524)
				)
				(justify mirror)
			)
		)
		(property "Device Type" "SC70-5H44"
			(at 2.3114 -10.414 0)
			(unlocked yes)
			(layer "B.Fab")
			(hide yes)
			(effects
				(font
					(size 1.016 1.016)
					(thickness 0.1524)
				)
				(justify mirror)
			)
		)
		(duplicate_pad_numbers_are_jumpers no)
		(fp_line
			(start -1.3843 -1.8034)
			(end -1.3843 -1.1176)
			(stroke
				(width 0.3302)
				(type default)
			)
			(layer "B.SilkS")
		)
		(fp_line
			(start -1.27 -1.7018)
			(end -1.27 1.7018)
			(stroke
				(width 0.1524)
				(type default)
			)
			(layer "B.SilkS")
		)
		(fp_line
			(start -1.27 1.7018)
			(end 1.27 1.7018)
			(stroke
				(width 0.1524)
				(type default)
			)
			(layer "B.SilkS")
		)
		(fp_line
			(start -0.6604 -1.8034)
			(end -1.3843 -1.8034)
			(stroke
				(width 0.3302)
				(type default)
			)
			(layer "B.SilkS")
		)
		(fp_line
			(start 1.27 -1.7018)
			(end -1.27 -1.7018)
			(stroke
				(width 0.1524)
				(type default)
			)
			(layer "B.SilkS")
		)
		(fp_line
			(start 1.27 1.7018)
			(end 1.27 -1.7018)
			(stroke
				(width 0.1524)
				(type default)
			)
			(layer "B.SilkS")
		)
		(fp_rect
			(start 1.524 1.9558)
			(end -1.524 -1.9558)
			(stroke
				(width 0)
				(type default)
			)
			(fill no)
			(layer "B.CrtYd")
		)
		(fp_poly
			(pts
				(xy 1.524 -1.9558) (xy -1.524 -1.9558) (xy -1.524 1.9558) (xy 1.524 1.9558)
			)
			(stroke
				(width 0)
				(type default)
			)
			(fill no)
			(layer "B.Fab")
		)
		(pad "1" smd rect
			(at -0.65024 -0.8255 180)
			(size 0.4064 1.2192)
			(layers "B.Cu" "B.Mask" "B.Paste")
			(net "Net_287")
		)
		(pad "2" smd rect
			(at 0 -0.8255 180)
			(size 0.4064 1.2192)
			(layers "B.Cu" "B.Mask" "B.Paste")
			(net "PG_STAT")
		)
		(pad "3" smd rect
			(at 0.65024 -0.8255 180)
			(size 0.4064 1.2192)
			(layers "B.Cu" "B.Mask" "B.Paste")
			(net "GND")
		)
		(pad "4" smd rect
			(at 0.65024 0.8255 180)
			(size 0.4064 1.2192)
			(layers "B.Cu" "B.Mask" "B.Paste")
			(net "PWRGD_P0V955_C")
		)
		(pad "5" smd rect
			(at -0.65024 0.8255 180)
			(size 0.4064 1.2192)
			(layers "B.Cu" "B.Mask" "B.Paste")
			(net "P1V8_C")
		)
	)
	(footprint ""
		(layer "B.Cu")
		(at 290.771072 -172.538136 180)
		(property "Reference" "C213"
			(at 0 0 0)
			(layer "B.SilkS")
			(hide yes)
			(effects
				(font
					(size 1.27 1.27)
				)
				(justify mirror)
			)
		)
		(property "Value" "SC1U10V2KX-1GP"
			(at -1.1811 -2.7051 180)
			(unlocked yes)
			(layer "B.Fab")
			(hide yes)
			(effects
				(font
					(size 1.016 1.016)
					(thickness 0.1524)
				)
				(justify mirror)
			)
		)
		(property "Device Type" "C402H22"
			(at -1.1811 -4.2291 180)
			(unlocked yes)
			(layer "B.Fab")
			(hide yes)
			(effects
				(font
					(size 1.016 1.016)
					(thickness 0.1524)
				)
				(justify mirror)
			)
		)
		(duplicate_pad_numbers_are_jumpers no)
		(fp_rect
			(start 0.4318 0.9525)
			(end -0.4318 -0.9525)
			(stroke
				(width 0)
				(type default)
			)
			(fill no)
			(layer "B.CrtYd")
		)
		(fp_rect
			(start 0.4318 0.9525)
			(end -0.4318 -0.9525)
			(stroke
				(width 0)
				(type default)
			)
			(fill no)
			(layer "B.Fab")
		)
		(pad "1" smd custom
			(at 0 -0.4445)
			(size 0.1524 0.1524)
			(layers "B.Cu" "B.Mask" "B.Paste")
			(net "P1V26_STBY")
			(options
				(clearance outline)
				(anchor circle)
			)
			(primitives
				(gr_poly
					(pts
						(arc
							(start 0.3048 0.2032)
							(mid 0.275042 0.275042)
							(end 0.2032 0.3048)
						)
						(arc
							(start -0.2032 0.3048)
							(mid -0.275042 0.275042)
							(end -0.3048 0.2032)
						)
						(arc
							(start -0.3048 -0.2032)
							(mid -0.275042 -0.275042)
							(end -0.2032 -0.3048)
						)
						(arc
							(start 0.2032 -0.3048)
							(mid 0.275042 -0.275042)
							(end 0.3048 -0.2032)
						)
					)
					(width 0)
					(fill yes)
				)
			)
		)
		(pad "2" smd custom
			(at 0 0.4445)
			(size 0.1524 0.1524)
			(layers "B.Cu" "B.Mask" "B.Paste")
			(net "GND")
			(options
				(clearance outline)
				(anchor circle)
			)
			(primitives
				(gr_poly
					(pts
						(arc
							(start 0.3048 0.2032)
							(mid 0.275042 0.275042)
							(end 0.2032 0.3048)
						)
						(arc
							(start -0.2032 0.3048)
							(mid -0.275042 0.275042)
							(end -0.3048 0.2032)
						)
						(arc
							(start -0.3048 -0.2032)
							(mid -0.275042 -0.275042)
							(end -0.2032 -0.3048)
						)
						(arc
							(start 0.2032 -0.3048)
							(mid 0.275042 -0.275042)
							(end 0.3048 -0.2032)
						)
					)
					(width 0)
					(fill yes)
				)
			)
		)
	)
	(footprint ""
		(layer "B.Cu")
		(at 96.715326 -38.94836 180)
		(property "Reference" "SC954"
			(at 0 0 0)
			(layer "B.SilkS")
			(hide yes)
			(effects
				(font
					(size 1.27 1.27)
				)
				(justify mirror)
			)
		)
		(property "Value" "SCD1U6D3V1KX-GP"
			(at 2.8321 -1.7399 180)
			(unlocked yes)
			(layer "B.Fab")
			(hide yes)
			(effects
				(font
					(size 1.016 1.016)
					(thickness 0.1524)
				)
				(justify mirror)
			)
		)
		(property "Device Type" "C0201H13"
			(at 2.8321 -3.2639 180)
			(unlocked yes)
			(layer "B.Fab")
			(hide yes)
			(effects
				(font
					(size 1.016 1.016)
					(thickness 0.1524)
				)
				(justify mirror)
			)
		)
		(duplicate_pad_numbers_are_jumpers no)
		(fp_rect
			(start 0.2794 0.6477)
			(end -0.2794 -0.6477)
			(stroke
				(width 0)
				(type default)
			)
			(fill no)
			(layer "B.CrtYd")
		)
		(fp_rect
			(start 0.2794 0.6477)
			(end -0.2794 -0.6477)
			(stroke
				(width 0)
				(type default)
			)
			(fill no)
			(layer "B.Fab")
		)
		(pad "1" smd custom
			(at 0 -0.2794)
			(size 0.0762 0.0762)
			(layers "B.Cu" "B.Mask" "B.Paste")
			(net "PCE_AVDD")
			(options
				(clearance outline)
				(anchor circle)
			)
			(primitives
				(gr_poly
					(pts
						(arc
							(start 0.1524 0.127)
							(mid 0.137521 0.162921)
							(end 0.1016 0.1778)
						)
						(arc
							(start -0.1016 0.1778)
							(mid -0.137521 0.162921)
							(end -0.1524 0.127)
						)
						(arc
							(start -0.1524 -0.127)
							(mid -0.137521 -0.162921)
							(end -0.1016 -0.1778)
						)
						(arc
							(start 0.1016 -0.1778)
							(mid 0.137521 -0.162921)
							(end 0.1524 -0.127)
						)
					)
					(width 0)
					(fill yes)
				)
			)
		)
		(pad "2" smd custom
			(at 0 0.2794)
			(size 0.0762 0.0762)
			(layers "B.Cu" "B.Mask" "B.Paste")
			(net "GND")
			(options
				(clearance outline)
				(anchor circle)
			)
			(primitives
				(gr_poly
					(pts
						(arc
							(start 0.1524 0.127)
							(mid 0.137521 0.162921)
							(end 0.1016 0.1778)
						)
						(arc
							(start -0.1016 0.1778)
							(mid -0.137521 0.162921)
							(end -0.1524 0.127)
						)
						(arc
							(start -0.1524 -0.127)
							(mid -0.137521 -0.162921)
							(end -0.1016 -0.1778)
						)
						(arc
							(start 0.1016 -0.1778)
							(mid 0.137521 -0.162921)
							(end 0.1524 -0.127)
						)
					)
					(width 0)
					(fill yes)
				)
			)
		)
	)
	(footprint ""
		(layer "B.Cu")
		(at 141.351 -46.863)
		(property "Reference" "STP121"
			(at 0 0 0)
			(layer "B.SilkS")
			(hide yes)
			(effects
				(font
					(size 1.27 1.27)
				)
				(justify mirror)
			)
		)
		(property "Value" "TPAD28"
			(at -0.0127 -1.8034 0)
			(unlocked yes)
			(layer "B.Fab")
			(hide yes)
			(effects
				(font
					(size 1.016 1.016)
					(thickness 0.1524)
				)
				(justify mirror)
			)
		)
		(property "Device Type" "TPAD28"
			(at -0.0127 -3.3274 0)
			(unlocked yes)
			(layer "B.Fab")
			(hide yes)
			(effects
				(font
					(size 1.016 1.016)
					(thickness 0.1524)
				)
				(justify mirror)
			)
		)
		(duplicate_pad_numbers_are_jumpers no)
		(fp_poly
			(pts
				(arc
					(start 0.3556 0)
					(mid -0.3556 0)
					(end 0.3556 0)
				)
			)
			(stroke
				(width 0)
				(type default)
			)
			(fill no)
			(layer "B.CrtYd")
		)
		(fp_poly
			(pts
				(arc
					(start 0.6096 0)
					(mid -0.6096 0)
					(end 0.6096 0)
				)
			)
			(stroke
				(width 0)
				(type default)
			)
			(fill no)
			(layer "B.Fab")
		)
		(pad "1" smd circle
			(at 0 0 180)
			(size 0.7112 0.7112)
			(layers "B.Cu" "B.Mask" "B.Paste")
			(net "XM_ADDR_21")
		)
	)
	(footprint ""
		(layer "B.Cu")
		(at 331.851 -164.338 180)
		(property "Reference" "C4"
			(at 0 0 0)
			(layer "B.SilkS")
			(hide yes)
			(effects
				(font
					(size 1.27 1.27)
				)
				(justify mirror)
			)
		)
		(property "Value" "SCD1U16V2KX-3GP"
			(at -1.1811 -2.7051 180)
			(unlocked yes)
			(layer "B.Fab")
			(hide yes)
			(effects
				(font
					(size 1.016 1.016)
					(thickness 0.1524)
				)
				(justify mirror)
			)
		)
		(property "Device Type" "C402H22"
			(at -1.1811 -4.2291 180)
			(unlocked yes)
			(layer "B.Fab")
			(hide yes)
			(effects
				(font
					(size 1.016 1.016)
					(thickness 0.1524)
				)
				(justify mirror)
			)
		)
		(duplicate_pad_numbers_are_jumpers no)
		(fp_rect
			(start 0.4318 0.9525)
			(end -0.4318 -0.9525)
			(stroke
				(width 0)
				(type default)
			)
			(fill no)
			(layer "B.CrtYd")
		)
		(fp_rect
			(start 0.4318 0.9525)
			(end -0.4318 -0.9525)
			(stroke
				(width 0)
				(type default)
			)
			(fill no)
			(layer "B.Fab")
		)
		(pad "1" smd custom
			(at 0 -0.4445)
			(size 0.1524 0.1524)
			(layers "B.Cu" "B.Mask" "B.Paste")
			(net "P3V3_STBY")
			(options
				(clearance outline)
				(anchor circle)
			)
			(primitives
				(gr_poly
					(pts
						(arc
							(start 0.3048 0.2032)
							(mid 0.275042 0.275042)
							(end 0.2032 0.3048)
						)
						(arc
							(start -0.2032 0.3048)
							(mid -0.275042 0.275042)
							(end -0.3048 0.2032)
						)
						(arc
							(start -0.3048 -0.2032)
							(mid -0.275042 -0.275042)
							(end -0.2032 -0.3048)
						)
						(arc
							(start 0.2032 -0.3048)
							(mid 0.275042 -0.275042)
							(end 0.3048 -0.2032)
						)
					)
					(width 0)
					(fill yes)
				)
			)
		)
		(pad "2" smd custom
			(at 0 0.4445)
			(size 0.1524 0.1524)
			(layers "B.Cu" "B.Mask" "B.Paste")
			(net "GND")
			(options
				(clearance outline)
				(anchor circle)
			)
			(primitives
				(gr_poly
					(pts
						(arc
							(start 0.3048 0.2032)
							(mid 0.275042 0.275042)
							(end 0.2032 0.3048)
						)
						(arc
							(start -0.2032 0.3048)
							(mid -0.275042 0.275042)
							(end -0.3048 0.2032)
						)
						(arc
							(start -0.3048 -0.2032)
							(mid -0.275042 -0.275042)
							(end -0.2032 -0.3048)
						)
						(arc
							(start 0.2032 -0.3048)
							(mid 0.275042 -0.275042)
							(end 0.3048 -0.2032)
						)
					)
					(width 0)
					(fill yes)
				)
			)
		)
	)
	(footprint ""
		(layer "B.Cu")
		(at 185.855864 -28.266136 180)
		(property "Reference" "C231"
			(at 0 0 0)
			(layer "B.SilkS")
			(hide yes)
			(effects
				(font
					(size 1.27 1.27)
				)
				(justify mirror)
			)
		)
		(property "Value" "SCD1U16V2KX-3GP"
			(at -1.1811 -2.7051 180)
			(unlocked yes)
			(layer "B.Fab")
			(hide yes)
			(effects
				(font
					(size 1.016 1.016)
					(thickness 0.1524)
				)
				(justify mirror)
			)
		)
		(property "Device Type" "C402H22"
			(at -1.1811 -4.2291 180)
			(unlocked yes)
			(layer "B.Fab")
			(hide yes)
			(effects
				(font
					(size 1.016 1.016)
					(thickness 0.1524)
				)
				(justify mirror)
			)
		)
		(duplicate_pad_numbers_are_jumpers no)
		(fp_rect
			(start 0.4318 0.9525)
			(end -0.4318 -0.9525)
			(stroke
				(width 0)
				(type default)
			)
			(fill no)
			(layer "B.CrtYd")
		)
		(fp_rect
			(start 0.4318 0.9525)
			(end -0.4318 -0.9525)
			(stroke
				(width 0)
				(type default)
			)
			(fill no)
			(layer "B.Fab")
		)
		(pad "1" smd custom
			(at 0 -0.4445)
			(size 0.1524 0.1524)
			(layers "B.Cu" "B.Mask" "B.Paste")
			(net "P3V3_STBY")
			(options
				(clearance outline)
				(anchor circle)
			)
			(primitives
				(gr_poly
					(pts
						(arc
							(start 0.3048 0.2032)
							(mid 0.275042 0.275042)
							(end 0.2032 0.3048)
						)
						(arc
							(start -0.2032 0.3048)
							(mid -0.275042 0.275042)
							(end -0.3048 0.2032)
						)
						(arc
							(start -0.3048 -0.2032)
							(mid -0.275042 -0.275042)
							(end -0.2032 -0.3048)
						)
						(arc
							(start 0.2032 -0.3048)
							(mid 0.275042 -0.275042)
							(end 0.3048 -0.2032)
						)
					)
					(width 0)
					(fill yes)
				)
			)
		)
		(pad "2" smd custom
			(at 0 0.4445)
			(size 0.1524 0.1524)
			(layers "B.Cu" "B.Mask" "B.Paste")
			(net "GND")
			(options
				(clearance outline)
				(anchor circle)
			)
			(primitives
				(gr_poly
					(pts
						(arc
							(start 0.3048 0.2032)
							(mid 0.275042 0.275042)
							(end 0.2032 0.3048)
						)
						(arc
							(start -0.2032 0.3048)
							(mid -0.275042 0.275042)
							(end -0.3048 0.2032)
						)
						(arc
							(start -0.3048 -0.2032)
							(mid -0.275042 -0.275042)
							(end -0.2032 -0.3048)
						)
						(arc
							(start 0.2032 -0.3048)
							(mid 0.275042 -0.275042)
							(end 0.3048 -0.2032)
						)
					)
					(width 0)
					(fill yes)
				)
			)
		)
	)
	(footprint ""
		(layer "B.Cu")
		(at 103.26497 -82.55)
		(property "Reference" "SR794"
			(at 0 0 0)
			(layer "B.SilkS")
			(hide yes)
			(effects
				(font
					(size 1.27 1.27)
				)
				(justify mirror)
			)
		)
		(property "Value" "10KR2F-2-GP"
			(at -0.064008 -3.993896 0)
			(unlocked yes)
			(layer "B.Fab")
			(hide yes)
			(effects
				(font
					(size 1.016 1.016)
					(thickness 0.1524)
				)
				(justify mirror)
			)
		)
		(property "Device Type" "R402H16"
			(at -0.064008 -5.517896 0)
			(unlocked yes)
			(layer "B.Fab")
			(hide yes)
			(effects
				(font
					(size 1.016 1.016)
					(thickness 0.1524)
				)
				(justify mirror)
			)
		)
		(duplicate_pad_numbers_are_jumpers no)
		(fp_line
			(start -0.508 -0.9398)
			(end 0.508 -0.9398)
			(stroke
				(width 0.1524)
				(type default)
			)
			(layer "B.SilkS")
		)
		(fp_line
			(start 0.508 -0.9398)
			(end 0.508 0.9398)
			(stroke
				(width 0.1524)
				(type default)
			)
			(layer "B.SilkS")
		)
		(fp_rect
			(start 0.508 0.9398)
			(end -0.508 -0.9398)
			(stroke
				(width 0)
				(type default)
			)
			(fill no)
			(layer "B.CrtYd")
		)
		(fp_rect
			(start 0.508 0.9398)
			(end -0.508 -0.9398)
			(stroke
				(width 0)
				(type default)
			)
			(fill no)
			(layer "B.Fab")
		)
		(pad "1" smd custom
			(at 0 -0.4445 180)
			(size 0.1397 0.1397)
			(layers "B.Cu" "B.Mask" "B.Paste")
			(net "SOFT_RESET_N")
			(options
				(clearance outline)
				(anchor circle)
			)
			(primitives
				(gr_poly
					(pts
						(arc
							(start -0.1778 0.2794)
							(mid -0.249642 0.249642)
							(end -0.2794 0.1778)
						)
						(arc
							(start -0.2794 -0.1778)
							(mid -0.249642 -0.249642)
							(end -0.1778 -0.2794)
						)
						(arc
							(start 0.1778 -0.2794)
							(mid 0.249642 -0.249642)
							(end 0.2794 -0.1778)
						)
						(arc
							(start 0.2794 0.1778)
							(mid 0.249642 0.249642)
							(end 0.1778 0.2794)
						)
					)
					(width 0)
					(fill yes)
				)
			)
		)
		(pad "2" smd custom
			(at 0 0.4445 180)
			(size 0.1397 0.1397)
			(layers "B.Cu" "B.Mask" "B.Paste")
			(net "P1V8_E")
			(options
				(clearance outline)
				(anchor circle)
			)
			(primitives
				(gr_poly
					(pts
						(arc
							(start -0.1778 0.2794)
							(mid -0.249642 0.249642)
							(end -0.2794 0.1778)
						)
						(arc
							(start -0.2794 -0.1778)
							(mid -0.249642 -0.249642)
							(end -0.1778 -0.2794)
						)
						(arc
							(start 0.1778 -0.2794)
							(mid 0.249642 -0.249642)
							(end 0.2794 -0.1778)
						)
						(arc
							(start 0.2794 0.1778)
							(mid 0.249642 0.249642)
							(end 0.1778 0.2794)
						)
					)
					(width 0)
					(fill yes)
				)
			)
		)
	)
)
